# T6G (Grand Teton) — schematic netlist excerpt (pin names and nets, part order shuffled) for the footprints in the layout excerpt that follows; sources: Cadence DE-HDL packaged netlist, KiCad conversion of 04192023_DAF0TMB3IC0_F0TG_MB_C_brd_V02_OCP.brd

PC148_1  Q_CAP  0.1UF 25V 10% X7R  pkg 0402  page 205 : A = SW_P12V_AUX_PVDDIO_P0_FLT ; B = GND
PC6646  Q_CAP  100NF 50V 10% X7R  pkg C0402  page 365 : A = PV09_RETIMER_CPU1_VCCS ; B = GND

(kicad_pcb
	(version 20260206)
	(generator "pcbnew")
	(generator_version "10.0")
	(general
		(thickness 1.6)
		(legacy_teardrops no)
	)
	(paper "A4")
	(title_block
		(title "04192023_DAF0TMB3IC0_F0TG_MB_C_brd_V02_OCP.brd")
		(comment 1 "Grand Teton / footprints 100-101 of 8354")
	)
	(layers
		(0 "F.Cu" signal "TOP")
		(4 "In1.Cu" signal "GND")
		(6 "In2.Cu" signal "IN1")
		(8 "In3.Cu" signal "GND1")
		(10 "In4.Cu" signal "IN2")
		(12 "In5.Cu" signal "GND2")
		(14 "In6.Cu" signal "IN3")
		(16 "In7.Cu" signal "GND3")
		(18 "In8.Cu" signal "VCC")
		(20 "In9.Cu" signal "VCC1")
		(22 "In10.Cu" signal "GND4")
		(24 "In11.Cu" signal "IN4")
		(26 "In12.Cu" signal "GND5")
		(28 "In13.Cu" signal "IN5")
		(30 "In14.Cu" signal "GND6")
		(32 "In15.Cu" signal "IN6")
		(34 "In16.Cu" signal "GND7")
		(2 "B.Cu" signal "BOTTOM")
		(9 "F.Adhes" user "F.Adhesive")
		(11 "B.Adhes" user "B.Adhesive")
		(13 "F.Paste" user "Package Geometry/Pastemask Top")
		(15 "B.Paste" user "Package Geometry/Pastemask Bottom")
		(5 "F.SilkS" user "Ref Des/Silkscreen Top")
		(7 "B.SilkS" user "Ref Des/Silkscreen Bottom")
		(1 "F.Mask" user "Board Geometry/Soldermask Top")
		(3 "B.Mask" user "Board Geometry/Soldermask Bottom")
		(17 "Dwgs.User" user "User.Drawings")
		(19 "Cmts.User" user "User.Comments")
		(21 "Eco1.User" user "User.Eco1")
		(23 "Eco2.User" user "User.Eco2")
		(25 "Edge.Cuts" user "Board Geometry/Outline")
		(27 "Margin" user)
		(31 "F.CrtYd" user "Package Geometry/Place Bound Top")
		(29 "B.CrtYd" user "Package Geometry/Place Bound Bottom")
		(35 "F.Fab" user "Ref Des/Assembly Top")
		(33 "B.Fab" user "Ref Des/Assembly Bottom")
	)
	(footprint ""
		(layer "F.Cu")
		(at 296.22877 -351.100644)
		(property "Reference" "PC148_1"
			(at 0 0 0)
			(layer "F.SilkS")
			(hide yes)
			(effects
				(font
					(size 1.27 1.27)
				)
			)
		)
		(property "Value" ""
			(at 0 0 0)
			(layer "F.Fab")
			(effects
				(font
					(size 1.27 1.27)
				)
			)
		)
		(duplicate_pad_numbers_are_jumpers no)
		(fp_line
			(start -0.7874 -0.4064)
			(end 0.7874 -0.4064)
			(stroke
				(width 0.1524)
				(type default)
			)
			(layer "F.SilkS")
		)
		(fp_line
			(start -0.7874 0.4064)
			(end -0.7874 -0.4064)
			(stroke
				(width 0.1524)
				(type default)
			)
			(layer "F.SilkS")
		)
		(fp_line
			(start 0.7874 -0.4064)
			(end 0.7874 0.4064)
			(stroke
				(width 0.1524)
				(type default)
			)
			(layer "F.SilkS")
		)
		(fp_line
			(start 0.7874 0.4064)
			(end -0.7874 0.4064)
			(stroke
				(width 0.1524)
				(type default)
			)
			(layer "F.SilkS")
		)
		(fp_line
			(start -0.67945 -0.305054)
			(end -0.12065 -0.305054)
			(stroke
				(width 0.1)
				(type default)
			)
			(layer "F.Fab")
		)
		(fp_line
			(start -0.67945 0.3048)
			(end -0.67945 -0.305054)
			(stroke
				(width 0.1)
				(type default)
			)
			(layer "F.Fab")
		)
		(fp_line
			(start -0.12065 -0.305054)
			(end -0.12065 -0.2794)
			(stroke
				(width 0.1)
				(type default)
			)
			(layer "F.Fab")
		)
		(fp_line
			(start -0.12065 -0.2794)
			(end 0.12065 -0.2794)
			(stroke
				(width 0.1)
				(type default)
			)
			(layer "F.Fab")
		)
		(fp_line
			(start -0.12065 0.2794)
			(end -0.12065 0.3048)
			(stroke
				(width 0.1)
				(type default)
			)
			(layer "F.Fab")
		)
		(fp_line
			(start -0.12065 0.3048)
			(end -0.67945 0.3048)
			(stroke
				(width 0.1)
				(type default)
			)
			(layer "F.Fab")
		)
		(fp_line
			(start 0.120396 0.2794)
			(end -0.12065 0.2794)
			(stroke
				(width 0.1)
				(type default)
			)
			(layer "F.Fab")
		)
		(fp_line
			(start 0.120396 0.3048)
			(end 0.120396 0.2794)
			(stroke
				(width 0.1)
				(type default)
			)
			(layer "F.Fab")
		)
		(fp_line
			(start 0.12065 -0.3048)
			(end 0.67945 -0.3048)
			(stroke
				(width 0.1)
				(type default)
			)
			(layer "F.Fab")
		)
		(fp_line
			(start 0.12065 -0.2794)
			(end 0.12065 -0.3048)
			(stroke
				(width 0.1)
				(type default)
			)
			(layer "F.Fab")
		)
		(fp_line
			(start 0.67945 -0.3048)
			(end 0.67945 0.3048)
			(stroke
				(width 0.1)
				(type default)
			)
			(layer "F.Fab")
		)
		(fp_line
			(start 0.67945 0.3048)
			(end 0.120396 0.3048)
			(stroke
				(width 0.1)
				(type default)
			)
			(layer "F.Fab")
		)
		(pad "1" smd circle
			(at -0.40005 0)
			(size 0 0)
			(layers "F.Cu" "F.Mask" "F.Paste")
			(net "SW_P12V_AUX_PVDDIO_P0_FLT")
		)
		(pad "2" smd circle
			(at 0.40005 0)
			(size 0 0)
			(layers "F.Cu" "F.Mask" "F.Paste")
			(net "GND")
		)
	)
	(footprint ""
		(layer "F.Cu")
		(at 22.147784 -393.539726 180)
		(property "Reference" "PC6646"
			(at 0 0 180)
			(layer "F.SilkS")
			(hide yes)
			(effects
				(font
					(size 1.27 1.27)
				)
			)
		)
		(property "Value" ""
			(at 0 0 180)
			(layer "F.Fab")
			(effects
				(font
					(size 1.27 1.27)
				)
			)
		)
		(duplicate_pad_numbers_are_jumpers no)
		(fp_line
			(start 0.7874 0.4064)
			(end -0.7874 0.4064)
			(stroke
				(width 0.1524)
				(type default)
			)
			(layer "F.SilkS")
		)
		(fp_line
			(start 0.7874 -0.4064)
			(end 0.7874 0.4064)
			(stroke
				(width 0.1524)
				(type default)
			)
			(layer "F.SilkS")
		)
		(fp_line
			(start -0.7874 0.4064)
			(end -0.7874 -0.4064)
			(stroke
				(width 0.1524)
				(type default)
			)
			(layer "F.SilkS")
		)
		(fp_line
			(start -0.7874 -0.4064)
			(end 0.7874 -0.4064)
			(stroke
				(width 0.1524)
				(type default)
			)
			(layer "F.SilkS")
		)
		(fp_line
			(start 0.67945 0.3048)
			(end 0.120396 0.3048)
			(stroke
				(width 0.1)
				(type default)
			)
			(layer "F.Fab")
		)
		(fp_line
			(start 0.67945 -0.3048)
			(end 0.67945 0.3048)
			(stroke
				(width 0.1)
				(type default)
			)
			(layer "F.Fab")
		)
		(fp_line
			(start 0.12065 -0.2794)
			(end 0.12065 -0.3048)
			(stroke
				(width 0.1)
				(type default)
			)
			(layer "F.Fab")
		)
		(fp_line
			(start 0.12065 -0.3048)
			(end 0.67945 -0.3048)
			(stroke
				(width 0.1)
				(type default)
			)
			(layer "F.Fab")
		)
		(fp_line
			(start 0.120396 0.3048)
			(end 0.120396 0.2794)
			(stroke
				(width 0.1)
				(type default)
			)
			(layer "F.Fab")
		)
		(fp_line
			(start 0.120396 0.2794)
			(end -0.12065 0.2794)
			(stroke
				(width 0.1)
				(type default)
			)
			(layer "F.Fab")
		)
		(fp_line
			(start -0.12065 0.3048)
			(end -0.67945 0.3048)
			(stroke
				(width 0.1)
				(type default)
			)
			(layer "F.Fab")
		)
		(fp_line
			(start -0.12065 0.2794)
			(end -0.12065 0.3048)
			(stroke
				(width 0.1)
				(type default)
			)
			(layer "F.Fab")
		)
		(fp_line
			(start -0.12065 -0.2794)
			(end 0.12065 -0.2794)
			(stroke
				(width 0.1)
				(type default)
			)
			(layer "F.Fab")
		)
		(fp_line
			(start -0.12065 -0.305054)
			(end -0.12065 -0.2794)
			(stroke
				(width 0.1)
				(type default)
			)
			(layer "F.Fab")
		)
		(fp_line
			(start -0.67945 0.3048)
			(end -0.67945 -0.305054)
			(stroke
				(width 0.1)
				(type default)
			)
			(layer "F.Fab")
		)
		(fp_line
			(start -0.67945 -0.305054)
			(end -0.12065 -0.305054)
			(stroke
				(width 0.1)
				(type default)
			)
			(layer "F.Fab")
		)
		(pad "1" smd circle
			(at -0.40005 0 180)
			(size 0 0)
			(layers "F.Cu" "F.Mask" "F.Paste")
			(net "PV09_RETIMER_CPU1_VCCS")
		)
		(pad "2" smd circle
			(at 0.40005 0 180)
			(size 0 0)
			(layers "F.Cu" "F.Mask" "F.Paste")
			(net "GND")
		)
	)
)
